(kicad_pcb
	(version 20260206)
	(generator "pcbnew")
	(generator_version "10.0")
	(general
		(thickness 1.6)
		(legacy_teardrops no)
	)
	(paper "A4")
	(title_block
		(title "dpb — 14545-sa.0730WZS0815.brd")
		(comment 1 "Honey Badger (Wiwynn) / footprints 556-563 of 1066")
	)
	(layers
		(0 "F.Cu" signal "TOP")
		(4 "In1.Cu" signal "L2GND")
		(6 "In2.Cu" signal "L3")
		(8 "In3.Cu" signal "L4VCC")
		(10 "In4.Cu" signal "L5VCC")
		(12 "In5.Cu" signal "L6")
		(14 "In6.Cu" signal "L7GND")
		(2 "B.Cu" signal "BOTTOM")
		(9 "F.Adhes" user "F.Adhesive")
		(11 "B.Adhes" user "B.Adhesive")
		(13 "F.Paste" user "Package Geometry/Pastemask Top")
		(15 "B.Paste" user "Package Geometry/Pastemask Bottom")
		(5 "F.SilkS" user "Ref Des/Silkscreen Top")
		(7 "B.SilkS" user "Ref Des/Silkscreen Bottom")
		(1 "F.Mask" user "Board Geometry/Soldermask Top")
		(3 "B.Mask" user "Board Geometry/Soldermask Bottom")
		(17 "Dwgs.User" user "User.Drawings")
		(19 "Cmts.User" user "User.Comments")
		(21 "Eco1.User" user "User.Eco1")
		(23 "Eco2.User" user "User.Eco2")
		(25 "Edge.Cuts" user "Board Geometry/Outline")
		(27 "Margin" user)
		(31 "F.CrtYd" user "Package Geometry/Place Bound Top")
		(29 "B.CrtYd" user "Package Geometry/Place Bound Bottom")
		(35 "F.Fab" user "Ref Des/Assembly Top")
		(33 "B.Fab" user "Ref Des/Assembly Bottom")
	)
	(footprint ""
		(layer "F.Cu")
		(at 14.495272 -500.446548 180)
		(property "Reference" "PC37"
			(at 0 0 180)
			(layer "F.SilkS")
			(hide yes)
			(effects
				(font
					(size 1.27 1.27)
				)
			)
		)
		(property "Value" "SC22U25V5MX-GP"
			(at -0.0762 -6.1214 180)
			(unlocked yes)
			(layer "F.Fab")
			(hide yes)
			(effects
				(font
					(size 1.016 1.016)
					(thickness 0.1524)
				)
			)
		)
		(property "Device Type" "C805H58"
			(at -0.0762 -8.1534 180)
			(unlocked yes)
			(layer "F.Fab")
			(hide yes)
			(effects
				(font
					(size 1.016 1.016)
					(thickness 0.1524)
				)
			)
		)
		(duplicate_pad_numbers_are_jumpers no)
		(fp_line
			(start 0.635 0)
			(end -0.635 0)
			(stroke
				(width 0.508)
				(type default)
			)
			(layer "F.SilkS")
		)
		(fp_rect
			(start -0.9652 1.778)
			(end 0.9652 -1.778)
			(stroke
				(width 0)
				(type default)
			)
			(fill no)
			(layer "F.CrtYd")
		)
		(fp_poly
			(pts
				(xy -0.9652 -1.778) (xy 0.9652 -1.778) (xy 0.9652 1.778) (xy -0.9652 1.778)
			)
			(stroke
				(width 0)
				(type default)
			)
			(fill no)
			(layer "F.Fab")
		)
		(pad "1" smd rect
			(at 0 -0.9652 180)
			(size 1.397 1.143)
			(layers "F.Cu" "F.Mask" "F.Paste")
			(net "P5VC_12VIN")
		)
		(pad "2" smd rect
			(at 0 0.9652 180)
			(size 1.397 1.143)
			(layers "F.Cu" "F.Mask" "F.Paste")
			(net "GND")
		)
	)
	(footprint ""
		(layer "F.Cu")
		(at 44.830746 -212.118702)
		(property "Reference" "R280"
			(at 0 0 0)
			(layer "F.SilkS")
			(hide yes)
			(effects
				(font
					(size 1.27 1.27)
				)
			)
		)
		(property "Value" "0R2J-2-GP"
			(at 0.064008 -3.993896 0)
			(unlocked yes)
			(layer "F.Fab")
			(hide yes)
			(effects
				(font
					(size 1.016 1.016)
					(thickness 0.1524)
				)
			)
		)
		(property "Device Type" "R402H16"
			(at 0.064008 -5.517896 0)
			(unlocked yes)
			(layer "F.Fab")
			(hide yes)
			(effects
				(font
					(size 1.016 1.016)
					(thickness 0.1524)
				)
			)
		)
		(duplicate_pad_numbers_are_jumpers no)
		(fp_line
			(start -0.508 -0.9398)
			(end -0.508 0.9398)
			(stroke
				(width 0.1524)
				(type default)
			)
			(layer "F.SilkS")
		)
		(fp_line
			(start 0.508 -0.9398)
			(end -0.508 -0.9398)
			(stroke
				(width 0.1524)
				(type default)
			)
			(layer "F.SilkS")
		)
		(fp_rect
			(start -0.508 0.9398)
			(end 0.508 -0.9398)
			(stroke
				(width 0)
				(type default)
			)
			(fill no)
			(layer "F.CrtYd")
		)
		(fp_rect
			(start -0.508 0.9398)
			(end 0.508 -0.9398)
			(stroke
				(width 0)
				(type default)
			)
			(fill no)
			(layer "F.Fab")
		)
		(pad "1" smd custom
			(at 0 -0.4445)
			(size 0.1397 0.1397)
			(layers "F.Cu" "F.Mask" "F.Paste")
			(net "SW_PWR_HDD12")
			(options
				(clearance outline)
				(anchor circle)
			)
			(primitives
				(gr_poly
					(pts
						(arc
							(start -0.1778 -0.2794)
							(mid -0.249642 -0.249642)
							(end -0.2794 -0.1778)
						)
						(arc
							(start -0.2794 0.1778)
							(mid -0.249642 0.249642)
							(end -0.1778 0.2794)
						)
						(arc
							(start 0.1778 0.2794)
							(mid 0.249642 0.249642)
							(end 0.2794 0.1778)
						)
						(arc
							(start 0.2794 -0.1778)
							(mid 0.249642 -0.249642)
							(end 0.1778 -0.2794)
						)
					)
					(width 0)
					(fill yes)
				)
			)
		)
		(pad "2" smd custom
			(at 0 0.4445)
			(size 0.1397 0.1397)
			(layers "F.Cu" "F.Mask" "F.Paste")
			(net "SW_PWR_R_HDD12")
			(options
				(clearance outline)
				(anchor circle)
			)
			(primitives
				(gr_poly
					(pts
						(arc
							(start -0.1778 -0.2794)
							(mid -0.249642 -0.249642)
							(end -0.2794 -0.1778)
						)
						(arc
							(start -0.2794 0.1778)
							(mid -0.249642 0.249642)
							(end -0.1778 0.2794)
						)
						(arc
							(start 0.1778 0.2794)
							(mid 0.249642 0.249642)
							(end 0.2794 0.1778)
						)
						(arc
							(start 0.2794 -0.1778)
							(mid 0.249642 -0.249642)
							(end 0.1778 -0.2794)
						)
					)
					(width 0)
					(fill yes)
				)
			)
		)
	)
	(footprint ""
		(layer "F.Cu")
		(at 33.019746 -57.0357 -90)
		(property "Reference" "C246"
			(at 0 0 270)
			(layer "F.SilkS")
			(hide yes)
			(effects
				(font
					(size 1.27 1.27)
				)
			)
		)
		(property "Value" "SCD01U50V2KX-1GP"
			(at 1.1811 -2.7051 270)
			(unlocked yes)
			(layer "F.Fab")
			(hide yes)
			(effects
				(font
					(size 1.016 1.016)
					(thickness 0.1524)
				)
			)
		)
		(property "Device Type" "C402H22"
			(at 1.1811 -4.2291 270)
			(unlocked yes)
			(layer "F.Fab")
			(hide yes)
			(effects
				(font
					(size 1.016 1.016)
					(thickness 0.1524)
				)
			)
		)
		(duplicate_pad_numbers_are_jumpers no)
		(fp_rect
			(start -0.4318 0.9525)
			(end 0.4318 -0.9525)
			(stroke
				(width 0)
				(type default)
			)
			(fill no)
			(layer "F.CrtYd")
		)
		(fp_rect
			(start -0.4318 0.9525)
			(end 0.4318 -0.9525)
			(stroke
				(width 0)
				(type default)
			)
			(fill no)
			(layer "F.Fab")
		)
		(pad "1" smd custom
			(at 0 -0.4445 270)
			(size 0.1524 0.1524)
			(layers "F.Cu" "F.Mask" "F.Paste")
			(net "SAS2X28_DRIVE_RX_N_A9")
			(options
				(clearance outline)
				(anchor circle)
			)
			(primitives
				(gr_poly
					(pts
						(arc
							(start 0.3048 -0.2032)
							(mid 0.275042 -0.275042)
							(end 0.2032 -0.3048)
						)
						(arc
							(start -0.2032 -0.3048)
							(mid -0.275042 -0.275042)
							(end -0.3048 -0.2032)
						)
						(arc
							(start -0.3048 0.2032)
							(mid -0.275042 0.275042)
							(end -0.2032 0.3048)
						)
						(arc
							(start 0.2032 0.3048)
							(mid 0.275042 0.275042)
							(end 0.3048 0.2032)
						)
					)
					(width 0)
					(fill yes)
				)
			)
		)
		(pad "2" smd custom
			(at 0 0.4445 270)
			(size 0.1524 0.1524)
			(layers "F.Cu" "F.Mask" "F.Paste")
			(net "SAS2X28_A_HDD9_RX_-")
			(options
				(clearance outline)
				(anchor circle)
			)
			(primitives
				(gr_poly
					(pts
						(arc
							(start 0.3048 -0.2032)
							(mid 0.275042 -0.275042)
							(end 0.2032 -0.3048)
						)
						(arc
							(start -0.2032 -0.3048)
							(mid -0.275042 -0.275042)
							(end -0.3048 -0.2032)
						)
						(arc
							(start -0.3048 0.2032)
							(mid -0.275042 0.275042)
							(end -0.2032 0.3048)
						)
						(arc
							(start 0.2032 0.3048)
							(mid 0.275042 0.275042)
							(end 0.3048 0.2032)
						)
					)
					(width 0)
					(fill yes)
				)
			)
		)
	)
	(footprint ""
		(layer "F.Cu")
		(at 230.364284 -145.004028 90)
		(property "Reference" "R142"
			(at 0 0 90)
			(layer "F.SilkS")
			(hide yes)
			(effects
				(font
					(size 1.27 1.27)
				)
			)
		)
		(property "Value" "10KR2F-2-GP"
			(at 0.064008 -3.993896 90)
			(unlocked yes)
			(layer "F.Fab")
			(hide yes)
			(effects
				(font
					(size 1.016 1.016)
					(thickness 0.1524)
				)
			)
		)
		(property "Device Type" "R402H16"
			(at 0.064008 -5.517896 90)
			(unlocked yes)
			(layer "F.Fab")
			(hide yes)
			(effects
				(font
					(size 1.016 1.016)
					(thickness 0.1524)
				)
			)
		)
		(duplicate_pad_numbers_are_jumpers no)
		(fp_line
			(start 0.508 -0.9398)
			(end -0.508 -0.9398)
			(stroke
				(width 0.1524)
				(type default)
			)
			(layer "F.SilkS")
		)
		(fp_line
			(start -0.508 -0.9398)
			(end -0.508 0.9398)
			(stroke
				(width 0.1524)
				(type default)
			)
			(layer "F.SilkS")
		)
		(fp_rect
			(start -0.508 0.9398)
			(end 0.508 -0.9398)
			(stroke
				(width 0)
				(type default)
			)
			(fill no)
			(layer "F.CrtYd")
		)
		(fp_rect
			(start -0.508 0.9398)
			(end 0.508 -0.9398)
			(stroke
				(width 0)
				(type default)
			)
			(fill no)
			(layer "F.Fab")
		)
		(pad "1" smd custom
			(at 0 -0.4445 90)
			(size 0.1397 0.1397)
			(layers "F.Cu" "F.Mask" "F.Paste")
			(net "P5VA")
			(options
				(clearance outline)
				(anchor circle)
			)
			(primitives
				(gr_poly
					(pts
						(arc
							(start -0.1778 -0.2794)
							(mid -0.249642 -0.249642)
							(end -0.2794 -0.1778)
						)
						(arc
							(start -0.2794 0.1778)
							(mid -0.249642 0.249642)
							(end -0.1778 0.2794)
						)
						(arc
							(start 0.1778 0.2794)
							(mid 0.249642 0.249642)
							(end 0.2794 0.1778)
						)
						(arc
							(start 0.2794 -0.1778)
							(mid 0.249642 -0.249642)
							(end 0.1778 -0.2794)
						)
					)
					(width 0)
					(fill yes)
				)
			)
		)
		(pad "2" smd custom
			(at 0 0.4445 90)
			(size 0.1397 0.1397)
			(layers "F.Cu" "F.Mask" "F.Paste")
			(net "DRIVE_ACT_3")
			(options
				(clearance outline)
				(anchor circle)
			)
			(primitives
				(gr_poly
					(pts
						(arc
							(start -0.1778 -0.2794)
							(mid -0.249642 -0.249642)
							(end -0.2794 -0.1778)
						)
						(arc
							(start -0.2794 0.1778)
							(mid -0.249642 0.249642)
							(end -0.1778 0.2794)
						)
						(arc
							(start 0.1778 0.2794)
							(mid 0.249642 0.249642)
							(end 0.2794 0.1778)
						)
						(arc
							(start 0.2794 -0.1778)
							(mid 0.249642 -0.249642)
							(end 0.1778 -0.2794)
						)
					)
					(width 0)
					(fill yes)
				)
			)
		)
	)
	(footprint ""
		(layer "F.Cu")
		(at 59.943746 -15.3797 90)
		(property "Reference" "PC14"
			(at 0 0 90)
			(layer "F.SilkS")
			(hide yes)
			(effects
				(font
					(size 1.27 1.27)
				)
			)
		)
		(property "Value" "SC22U25V5MX-GP"
			(at -0.0762 -6.1214 90)
			(unlocked yes)
			(layer "F.Fab")
			(hide yes)
			(effects
				(font
					(size 1.016 1.016)
					(thickness 0.1524)
				)
			)
		)
		(property "Device Type" "C805H58"
			(at -0.0762 -8.1534 90)
			(unlocked yes)
			(layer "F.Fab")
			(hide yes)
			(effects
				(font
					(size 1.016 1.016)
					(thickness 0.1524)
				)
			)
		)
		(duplicate_pad_numbers_are_jumpers no)
		(fp_line
			(start 0.635 0)
			(end -0.635 0)
			(stroke
				(width 0.508)
				(type default)
			)
			(layer "F.SilkS")
		)
		(fp_rect
			(start -0.9652 1.778)
			(end 0.9652 -1.778)
			(stroke
				(width 0)
				(type default)
			)
			(fill no)
			(layer "F.CrtYd")
		)
		(fp_poly
			(pts
				(xy -0.9652 -1.778) (xy 0.9652 -1.778) (xy 0.9652 1.778) (xy -0.9652 1.778)
			)
			(stroke
				(width 0)
				(type default)
			)
			(fill no)
			(layer "F.Fab")
		)
		(pad "1" smd rect
			(at 0 -0.9652 90)
			(size 1.397 1.143)
			(layers "F.Cu" "F.Mask" "F.Paste")
			(net "P5VB_12VIN")
		)
		(pad "2" smd rect
			(at 0 0.9652 90)
			(size 1.397 1.143)
			(layers "F.Cu" "F.Mask" "F.Paste")
			(net "GND")
		)
	)
	(footprint ""
		(layer "F.Cu")
		(at 162.572446 -458.631036)
		(property "Reference" "R388"
			(at 0 0 0)
			(layer "F.SilkS")
			(hide yes)
			(effects
				(font
					(size 1.27 1.27)
				)
			)
		)
		(property "Value" "10KR2F-2-GP"
			(at 0.064008 -3.993896 0)
			(unlocked yes)
			(layer "F.Fab")
			(hide yes)
			(effects
				(font
					(size 1.016 1.016)
					(thickness 0.1524)
				)
			)
		)
		(property "Device Type" "R402H16"
			(at 0.064008 -5.517896 0)
			(unlocked yes)
			(layer "F.Fab")
			(hide yes)
			(effects
				(font
					(size 1.016 1.016)
					(thickness 0.1524)
				)
			)
		)
		(duplicate_pad_numbers_are_jumpers no)
		(fp_line
			(start -0.508 -0.9398)
			(end -0.508 0.9398)
			(stroke
				(width 0.1524)
				(type default)
			)
			(layer "F.SilkS")
		)
		(fp_line
			(start 0.508 -0.9398)
			(end -0.508 -0.9398)
			(stroke
				(width 0.1524)
				(type default)
			)
			(layer "F.SilkS")
		)
		(fp_rect
			(start -0.508 0.9398)
			(end 0.508 -0.9398)
			(stroke
				(width 0)
				(type default)
			)
			(fill no)
			(layer "F.CrtYd")
		)
		(fp_rect
			(start -0.508 0.9398)
			(end 0.508 -0.9398)
			(stroke
				(width 0)
				(type default)
			)
			(fill no)
			(layer "F.Fab")
		)
		(pad "1" smd custom
			(at 0 -0.4445)
			(size 0.1397 0.1397)
			(layers "F.Cu" "F.Mask" "F.Paste")
			(net "P5VA")
			(options
				(clearance outline)
				(anchor circle)
			)
			(primitives
				(gr_poly
					(pts
						(arc
							(start -0.1778 -0.2794)
							(mid -0.249642 -0.249642)
							(end -0.2794 -0.1778)
						)
						(arc
							(start -0.2794 0.1778)
							(mid -0.249642 0.249642)
							(end -0.1778 0.2794)
						)
						(arc
							(start 0.1778 0.2794)
							(mid 0.249642 0.249642)
							(end 0.2794 0.1778)
						)
						(arc
							(start 0.2794 -0.1778)
							(mid 0.249642 -0.249642)
							(end 0.1778 -0.2794)
						)
					)
					(width 0)
					(fill yes)
				)
			)
		)
		(pad "2" smd custom
			(at 0 0.4445)
			(size 0.1397 0.1397)
			(layers "F.Cu" "F.Mask" "F.Paste")
			(net "P5VA_DIV")
			(options
				(clearance outline)
				(anchor circle)
			)
			(primitives
				(gr_poly
					(pts
						(arc
							(start -0.1778 -0.2794)
							(mid -0.249642 -0.249642)
							(end -0.2794 -0.1778)
						)
						(arc
							(start -0.2794 0.1778)
							(mid -0.249642 0.249642)
							(end -0.1778 0.2794)
						)
						(arc
							(start 0.1778 0.2794)
							(mid 0.249642 0.249642)
							(end 0.2794 0.1778)
						)
						(arc
							(start 0.2794 -0.1778)
							(mid 0.249642 -0.249642)
							(end 0.1778 -0.2794)
						)
					)
					(width 0)
					(fill yes)
				)
			)
		)
	)
	(footprint ""
		(layer "F.Cu")
		(at 51.028346 -347.3196 -90)
		(property "Reference" "R496"
			(at 0 0 270)
			(layer "F.SilkS")
			(hide yes)
			(effects
				(font
					(size 1.27 1.27)
				)
			)
		)
		(property "Value" "1KR2F-3-GP"
			(at 0.064008 -3.993896 270)
			(unlocked yes)
			(layer "F.Fab")
			(hide yes)
			(effects
				(font
					(size 1.016 1.016)
					(thickness 0.1524)
				)
			)
		)
		(property "Device Type" "R402H16"
			(at 0.064008 -5.517896 270)
			(unlocked yes)
			(layer "F.Fab")
			(hide yes)
			(effects
				(font
					(size 1.016 1.016)
					(thickness 0.1524)
				)
			)
		)
		(duplicate_pad_numbers_are_jumpers no)
		(fp_line
			(start -0.508 -0.9398)
			(end -0.508 0.9398)
			(stroke
				(width 0.1524)
				(type default)
			)
			(layer "F.SilkS")
		)
		(fp_line
			(start 0.508 -0.9398)
			(end -0.508 -0.9398)
			(stroke
				(width 0.1524)
				(type default)
			)
			(layer "F.SilkS")
		)
		(fp_rect
			(start -0.508 0.9398)
			(end 0.508 -0.9398)
			(stroke
				(width 0)
				(type default)
			)
			(fill no)
			(layer "F.CrtYd")
		)
		(fp_rect
			(start -0.508 0.9398)
			(end 0.508 -0.9398)
			(stroke
				(width 0)
				(type default)
			)
			(fill no)
			(layer "F.Fab")
		)
		(pad "1" smd custom
			(at 0 -0.4445 270)
			(size 0.1397 0.1397)
			(layers "F.Cu" "F.Mask" "F.Paste")
			(net "FLT_HDD6_B")
			(options
				(clearance outline)
				(anchor circle)
			)
			(primitives
				(gr_poly
					(pts
						(arc
							(start -0.1778 -0.2794)
							(mid -0.249642 -0.249642)
							(end -0.2794 -0.1778)
						)
						(arc
							(start -0.2794 0.1778)
							(mid -0.249642 0.249642)
							(end -0.1778 0.2794)
						)
						(arc
							(start 0.1778 0.2794)
							(mid 0.249642 0.249642)
							(end 0.2794 0.1778)
						)
						(arc
							(start 0.2794 -0.1778)
							(mid 0.249642 -0.249642)
							(end 0.1778 -0.2794)
						)
					)
					(width 0)
					(fill yes)
				)
			)
		)
		(pad "2" smd custom
			(at 0 0.4445 270)
			(size 0.1397 0.1397)
			(layers "F.Cu" "F.Mask" "F.Paste")
			(net "FLT_HDD6_DRIVE")
			(options
				(clearance outline)
				(anchor circle)
			)
			(primitives
				(gr_poly
					(pts
						(arc
							(start -0.1778 -0.2794)
							(mid -0.249642 -0.249642)
							(end -0.2794 -0.1778)
						)
						(arc
							(start -0.2794 0.1778)
							(mid -0.249642 0.249642)
							(end -0.1778 0.2794)
						)
						(arc
							(start 0.1778 0.2794)
							(mid 0.249642 0.249642)
							(end 0.2794 0.1778)
						)
						(arc
							(start 0.2794 -0.1778)
							(mid 0.249642 -0.249642)
							(end 0.1778 -0.2794)
						)
					)
					(width 0)
					(fill yes)
				)
			)
		)
	)
	(footprint ""
		(layer "F.Cu")
		(at 32.9946 -298.958 180)
		(property "Reference" "C223"
			(at 0 0 180)
			(layer "F.SilkS")
			(hide yes)
			(effects
				(font
					(size 1.27 1.27)
				)
			)
		)
		(property "Value" "SC10U25V6KX-1GP"
			(at -0.0762 -5.1308 180)
			(unlocked yes)
			(layer "F.Fab")
			(hide yes)
			(effects
				(font
					(size 1.016 1.016)
					(thickness 0.1524)
				)
			)
		)
		(property "Device Type" "C1206H71"
			(at -0.127 -6.6548 180)
			(unlocked yes)
			(layer "F.Fab")
			(hide yes)
			(effects
				(font
					(size 1.016 1.016)
					(thickness 0.1524)
				)
			)
		)
		(duplicate_pad_numbers_are_jumpers no)
		(fp_line
			(start 1.016 2.2352)
			(end -1.016 2.2352)
			(stroke
				(width 0.1524)
				(type default)
			)
			(layer "F.SilkS")
		)
		(fp_line
			(start 1.016 0.8382)
			(end 1.016 2.2352)
			(stroke
				(width 0.1524)
				(type default)
			)
			(layer "F.SilkS")
		)
		(fp_line
			(start 1.016 -2.2352)
			(end 1.016 -0.8382)
			(stroke
				(width 0.1524)
				(type default)
			)
			(layer "F.SilkS")
		)
		(fp_line
			(start -1.016 2.2352)
			(end -1.016 0.8382)
			(stroke
				(width 0.1524)
				(type default)
			)
			(layer "F.SilkS")
		)
		(fp_line
			(start -1.016 -0.8382)
			(end -1.016 -2.2352)
			(stroke
				(width 0.1524)
				(type default)
			)
			(layer "F.SilkS")
		)
		(fp_line
			(start -1.016 -2.2352)
			(end 1.016 -2.2352)
			(stroke
				(width 0.1524)
				(type default)
			)
			(layer "F.SilkS")
		)
		(fp_rect
			(start -1.0922 2.3114)
			(end 1.0922 -2.3114)
			(stroke
				(width 0)
				(type default)
			)
			(fill no)
			(layer "F.CrtYd")
		)
		(fp_poly
			(pts
				(xy 1.0922 -2.3114) (xy 1.0922 2.3114) (xy -1.0922 2.3114) (xy -1.0922 -2.3114)
			)
			(stroke
				(width 0)
				(type default)
			)
			(fill no)
			(layer "F.Fab")
		)
		(pad "1" smd rect
			(at 0 -1.397 180)
			(size 1.651 1.27)
			(layers "F.Cu" "F.Mask" "F.Paste")
			(net "P12V_HDD7")
		)
		(pad "2" smd rect
			(at 0 1.397 180)
			(size 1.651 1.27)
			(layers "F.Cu" "F.Mask" "F.Paste")
			(net "GND")
		)
	)
)
